#ISCELL
  mstr_misc dns *
  *
#ISCELL
  pure_quanta quanta_title_block_c *
  *
#ISCELL
  standard offpage *
  page248_i1
#ISCELL
  pure_quanta_power universal_power *
  page248_i10
#ISCELL
  standard offpage *
  page248_i11
#ISCELL
  standard offpage *
  page248_i12
#ISCELL
  pure_quanta_power universal_gnd *
  page248_i13
#CELL
  pure_quanta pca9617adp *
  page248_i14
#CELL
  pure_quanta q_cap *
  page248_i15
#ISCELL
  pure_quanta_power universal_gnd *
  page248_i16
#ISCELL
  pure_quanta_power universal_power *
  page248_i17
#ISCELL
  pure_quanta_power universal_power *
  page248_i18
#CELL
  pure_quanta q_cap *
  page248_i19
#ISCELL
  standard offpage *
  page248_i2
#ISCELL
  pure_quanta_power universal_gnd *
  page248_i20
#ISCELL
  pure_quanta_power universal_power *
  page248_i22
#CELL
  pure_quanta q_res *
  page248_i23
#ISCELL
  standard offpage *
  page248_i24
#ISCELL
  standard offpage *
  page248_i25
#CELL
  pure_quanta q_res *
  page248_i27
#ISCELL
  pure_quanta_power universal_power *
  page248_i28
#ISCELL
  standard offpage *
  page248_i29
#ISCELL
  pure_quanta_power universal_gnd *
  page248_i3
#ISCELL
  standard offpage *
  page248_i30
#CELL
  pure_quanta q_res *
  page248_i31
#ISCELL
  standard offpage *
  page248_i32
#ISCELL
  standard offpage *
  page248_i33
#CELL
  pure_quanta q_res *
  page248_i34
#CELL
  pure_quanta q_res *
  page248_i35
#ISCELL
  standard offpage *
  page248_i37
#CELL
  pure_quanta q_res *
  page248_i38
#CELL
  pure_quanta q_cap *
  page248_i4
#ISCELL
  standard offpage *
  page248_i40
#CELL
  pure_quanta q_res *
  page248_i41
#ISCELL
  standard offpage *
  page248_i42
#CELL
  pure_quanta q_res *
  page248_i43
#CELL
  pure_quanta q_res *
  page248_i44
#CELL
  pure_quanta q_res *
  page248_i45
#ISCELL
  standard offpage *
  page248_i46
#ISCELL
  pure_quanta_power universal_gnd *
  page248_i5
#CELL
  pure_quanta pca9617adp *
  page248_i6
#ISCELL
  pure_quanta_power universal_power *
  page248_i7
#ISCELL
  pure_quanta_power universal_gnd *
  page248_i8
#CELL
  pure_quanta q_cap *
  page248_i9
